# T6G (Grand Teton) — schematic netlist excerpt (pin names and nets, part order shuffled) for the footprints in the layout excerpt that follows; sources: Cadence DE-HDL packaged netlist, KiCad conversion of 04192023_DAF0TMB3IC0_F0TG_MB_C_brd_V02_OCP.brd

R6747  Q_RES  0 5% CHIP  pkg 0201LF  page 184 : A = SMB_RT_CPU1_P3_R_SCL ; B = SMB_RT_CPU1_P3_SCL
C2123  Q_CAP  22UF 4V 20% X6S  pkg C0402  page 74 : A = PVDDIO_P1 ; B = GND
R523  Q_RES  1K 1% CHIP  pkg 0402LF  page 54 : A = PVDD18_S5_P1 ; B = JTAG_CPU1_TDO

(kicad_pcb
	(version 20260206)
	(generator "pcbnew")
	(generator_version "10.0")
	(general
		(thickness 1.6)
		(legacy_teardrops no)
	)
	(paper "A4")
	(title_block
		(title "04192023_DAF0TMB3IC0_F0TG_MB_C_brd_V02_OCP.brd")
		(comment 1 "Grand Teton / footprints 6116-6118 of 8354")
	)
	(layers
		(0 "F.Cu" signal "TOP")
		(4 "In1.Cu" signal "GND")
		(6 "In2.Cu" signal "IN1")
		(8 "In3.Cu" signal "GND1")
		(10 "In4.Cu" signal "IN2")
		(12 "In5.Cu" signal "GND2")
		(14 "In6.Cu" signal "IN3")
		(16 "In7.Cu" signal "GND3")
		(18 "In8.Cu" signal "VCC")
		(20 "In9.Cu" signal "VCC1")
		(22 "In10.Cu" signal "GND4")
		(24 "In11.Cu" signal "IN4")
		(26 "In12.Cu" signal "GND5")
		(28 "In13.Cu" signal "IN5")
		(30 "In14.Cu" signal "GND6")
		(32 "In15.Cu" signal "IN6")
		(34 "In16.Cu" signal "GND7")
		(2 "B.Cu" signal "BOTTOM")
		(9 "F.Adhes" user "F.Adhesive")
		(11 "B.Adhes" user "B.Adhesive")
		(13 "F.Paste" user "Package Geometry/Pastemask Top")
		(15 "B.Paste" user "Package Geometry/Pastemask Bottom")
		(5 "F.SilkS" user "Ref Des/Silkscreen Top")
		(7 "B.SilkS" user "Ref Des/Silkscreen Bottom")
		(1 "F.Mask" user "Board Geometry/Soldermask Top")
		(3 "B.Mask" user "Board Geometry/Soldermask Bottom")
		(17 "Dwgs.User" user "User.Drawings")
		(19 "Cmts.User" user "User.Comments")
		(21 "Eco1.User" user "User.Eco1")
		(23 "Eco2.User" user "User.Eco2")
		(25 "Edge.Cuts" user "Board Geometry/Outline")
		(27 "Margin" user)
		(31 "F.CrtYd" user "Package Geometry/Place Bound Top")
		(29 "B.CrtYd" user "Package Geometry/Place Bound Bottom")
		(35 "F.Fab" user "Ref Des/Assembly Top")
		(33 "B.Fab" user "Ref Des/Assembly Bottom")
	)
	(footprint ""
		(layer "B.Cu")
		(at 98.578924 -257.930396 180)
		(property "Reference" "C2123"
			(at 0 0 0)
			(layer "B.SilkS")
			(hide yes)
			(effects
				(font
					(size 1.27 1.27)
				)
				(justify mirror)
			)
		)
		(property "Value" ""
			(at 0 0 0)
			(layer "B.Fab")
			(effects
				(font
					(size 1.27 1.27)
				)
				(justify mirror)
			)
		)
		(duplicate_pad_numbers_are_jumpers no)
		(fp_line
			(start 0.7874 0.4064)
			(end 0.7874 -0.4064)
			(stroke
				(width 0.1524)
				(type default)
			)
			(layer "B.SilkS")
		)
		(fp_line
			(start 0.7874 -0.4064)
			(end -0.7874 -0.4064)
			(stroke
				(width 0.1524)
				(type default)
			)
			(layer "B.SilkS")
		)
		(fp_line
			(start -0.7874 0.4064)
			(end 0.7874 0.4064)
			(stroke
				(width 0.1524)
				(type default)
			)
			(layer "B.SilkS")
		)
		(fp_line
			(start -0.7874 -0.4064)
			(end -0.7874 0.4064)
			(stroke
				(width 0.1524)
				(type default)
			)
			(layer "B.SilkS")
		)
		(fp_line
			(start 0.67945 0.3048)
			(end 0.67945 -0.305054)
			(stroke
				(width 0.1)
				(type default)
			)
			(layer "B.Fab")
		)
		(fp_line
			(start 0.67945 -0.305054)
			(end 0.12065 -0.305054)
			(stroke
				(width 0.1)
				(type default)
			)
			(layer "B.Fab")
		)
		(fp_line
			(start 0.12065 0.3048)
			(end 0.67945 0.3048)
			(stroke
				(width 0.1)
				(type default)
			)
			(layer "B.Fab")
		)
		(fp_line
			(start 0.12065 0.2794)
			(end 0.12065 0.3048)
			(stroke
				(width 0.1)
				(type default)
			)
			(layer "B.Fab")
		)
		(fp_line
			(start 0.12065 -0.2794)
			(end -0.12065 -0.2794)
			(stroke
				(width 0.1)
				(type default)
			)
			(layer "B.Fab")
		)
		(fp_line
			(start 0.12065 -0.305054)
			(end 0.12065 -0.2794)
			(stroke
				(width 0.1)
				(type default)
			)
			(layer "B.Fab")
		)
		(fp_line
			(start -0.120396 0.3048)
			(end -0.120396 0.2794)
			(stroke
				(width 0.1)
				(type default)
			)
			(layer "B.Fab")
		)
		(fp_line
			(start -0.120396 0.2794)
			(end 0.12065 0.2794)
			(stroke
				(width 0.1)
				(type default)
			)
			(layer "B.Fab")
		)
		(fp_line
			(start -0.12065 -0.2794)
			(end -0.12065 -0.3048)
			(stroke
				(width 0.1)
				(type default)
			)
			(layer "B.Fab")
		)
		(fp_line
			(start -0.12065 -0.3048)
			(end -0.67945 -0.3048)
			(stroke
				(width 0.1)
				(type default)
			)
			(layer "B.Fab")
		)
		(fp_line
			(start -0.67945 0.3048)
			(end -0.120396 0.3048)
			(stroke
				(width 0.1)
				(type default)
			)
			(layer "B.Fab")
		)
		(fp_line
			(start -0.67945 -0.3048)
			(end -0.67945 0.3048)
			(stroke
				(width 0.1)
				(type default)
			)
			(layer "B.Fab")
		)
		(pad "1" smd circle
			(at 0.40005 0)
			(size 0 0)
			(layers "B.Cu" "B.Mask" "B.Paste")
			(net "PVDDIO_P1")
		)
		(pad "2" smd circle
			(at -0.40005 0)
			(size 0 0)
			(layers "B.Cu" "B.Mask" "B.Paste")
			(net "GND")
		)
	)
	(footprint ""
		(layer "B.Cu")
		(at 153.357834 -199.234552 90)
		(property "Reference" "R523"
			(at 0 0 90)
			(layer "B.SilkS")
			(hide yes)
			(effects
				(font
					(size 1.27 1.27)
				)
				(justify mirror)
			)
		)
		(property "Value" ""
			(at 0 0 90)
			(layer "B.Fab")
			(effects
				(font
					(size 1.27 1.27)
				)
				(justify mirror)
			)
		)
		(duplicate_pad_numbers_are_jumpers no)
		(fp_line
			(start 0.7874 -0.4064)
			(end -0.7874 -0.4064)
			(stroke
				(width 0.1524)
				(type default)
			)
			(layer "B.SilkS")
		)
		(fp_line
			(start -0.7874 -0.4064)
			(end -0.7874 0.4064)
			(stroke
				(width 0.1524)
				(type default)
			)
			(layer "B.SilkS")
		)
		(fp_line
			(start 0.7874 0.4064)
			(end 0.7874 -0.4064)
			(stroke
				(width 0.1524)
				(type default)
			)
			(layer "B.SilkS")
		)
		(fp_line
			(start -0.7874 0.4064)
			(end 0.7874 0.4064)
			(stroke
				(width 0.1524)
				(type default)
			)
			(layer "B.SilkS")
		)
		(fp_line
			(start 0.67945 -0.305054)
			(end 0.12065 -0.305054)
			(stroke
				(width 0.1)
				(type default)
			)
			(layer "B.Fab")
		)
		(fp_line
			(start 0.12065 -0.305054)
			(end 0.12065 -0.2794)
			(stroke
				(width 0.1)
				(type default)
			)
			(layer "B.Fab")
		)
		(fp_line
			(start -0.12065 -0.3048)
			(end -0.67945 -0.3048)
			(stroke
				(width 0.1)
				(type default)
			)
			(layer "B.Fab")
		)
		(fp_line
			(start -0.67945 -0.3048)
			(end -0.67945 0.3048)
			(stroke
				(width 0.1)
				(type default)
			)
			(layer "B.Fab")
		)
		(fp_line
			(start 0.12065 -0.2794)
			(end -0.12065 -0.2794)
			(stroke
				(width 0.1)
				(type default)
			)
			(layer "B.Fab")
		)
		(fp_line
			(start -0.12065 -0.2794)
			(end -0.12065 -0.3048)
			(stroke
				(width 0.1)
				(type default)
			)
			(layer "B.Fab")
		)
		(fp_line
			(start 0.12065 0.2794)
			(end 0.12065 0.3048)
			(stroke
				(width 0.1)
				(type default)
			)
			(layer "B.Fab")
		)
		(fp_line
			(start -0.120396 0.2794)
			(end 0.12065 0.2794)
			(stroke
				(width 0.1)
				(type default)
			)
			(layer "B.Fab")
		)
		(fp_line
			(start 0.67945 0.3048)
			(end 0.67945 -0.305054)
			(stroke
				(width 0.1)
				(type default)
			)
			(layer "B.Fab")
		)
		(fp_line
			(start 0.12065 0.3048)
			(end 0.67945 0.3048)
			(stroke
				(width 0.1)
				(type default)
			)
			(layer "B.Fab")
		)
		(fp_line
			(start -0.120396 0.3048)
			(end -0.120396 0.2794)
			(stroke
				(width 0.1)
				(type default)
			)
			(layer "B.Fab")
		)
		(fp_line
			(start -0.67945 0.3048)
			(end -0.120396 0.3048)
			(stroke
				(width 0.1)
				(type default)
			)
			(layer "B.Fab")
		)
		(pad "1" smd circle
			(at 0.40005 0 270)
			(size 0 0)
			(layers "B.Cu" "B.Mask" "B.Paste")
			(net "PVDD18_S5_P1")
		)
		(pad "2" smd circle
			(at -0.40005 0 270)
			(size 0 0)
			(layers "B.Cu" "B.Mask" "B.Paste")
			(net "JTAG_CPU1_TDO")
		)
	)
	(footprint ""
		(layer "B.Cu")
		(at 217.678 -339.598 180)
		(property "Reference" "R6747"
			(at 0 0 0)
			(layer "B.SilkS")
			(hide yes)
			(effects
				(font
					(size 1.27 1.27)
				)
				(justify mirror)
			)
		)
		(property "Value" ""
			(at 0 0 0)
			(layer "B.Fab")
			(effects
				(font
					(size 1.27 1.27)
				)
				(justify mirror)
			)
		)
		(duplicate_pad_numbers_are_jumpers no)
		(fp_line
			(start 0.32512 0.175006)
			(end 0.32512 -0.175006)
			(stroke
				(width 0.1)
				(type default)
			)
			(layer "B.Fab")
		)
		(fp_line
			(start 0.32512 -0.175006)
			(end -0.32512 -0.175006)
			(stroke
				(width 0.1)
				(type default)
			)
			(layer "B.Fab")
		)
		(fp_line
			(start -0.32512 0.175006)
			(end 0.32512 0.175006)
			(stroke
				(width 0.1)
				(type default)
			)
			(layer "B.Fab")
		)
		(fp_line
			(start -0.32512 -0.175006)
			(end -0.32512 0.175006)
			(stroke
				(width 0.1)
				(type default)
			)
			(layer "B.Fab")
		)
		(pad "1" smd rect
			(at 0.2667 0)
			(size 0.3048 0.381)
			(layers "B.Cu" "B.Mask" "B.Paste")
			(net "SMB_RT_CPU1_P3_R_SCL")
		)
		(pad "2" smd rect
			(at -0.2667 0 180)
			(size 0.3048 0.381)
			(layers "B.Cu" "B.Mask" "B.Paste")
			(net "SMB_RT_CPU1_P3_SCL")
		)
	)
)
